(kicad_pcb
	(version 20260206)
	(generator "pcbnew")
	(generator_version "10.0")
	(general
		(thickness 1.6)
		(legacy_teardrops no)
	)
	(paper "A4")
	(title_block
		(title "timecard-production-celestica-r4006 — R4006-B0001-02_R01.brd")
		(comment 1 "Time Appliance Project (Time Card) / footprints 692-697 of 1113")
	)
	(layers
		(0 "F.Cu" signal "TOP")
		(4 "In1.Cu" signal "L02_GND1")
		(6 "In2.Cu" signal "L03_SIG1")
		(8 "In3.Cu" signal "L04_GND2")
		(10 "In4.Cu" signal "L05_VCC1")
		(12 "In5.Cu" signal "L06_VCC2")
		(14 "In6.Cu" signal "L07_GND3")
		(16 "In7.Cu" signal "L08_SIG2")
		(18 "In8.Cu" signal "L09_GND4")
		(2 "B.Cu" signal "BOTTOM")
		(9 "F.Adhes" user "F.Adhesive")
		(11 "B.Adhes" user "B.Adhesive")
		(13 "F.Paste" user "Package Geometry/Pastemask Top")
		(15 "B.Paste" user "Package Geometry/Pastemask Bottom")
		(5 "F.SilkS" user "Ref Des/Silkscreen Top")
		(7 "B.SilkS" user "Ref Des/Silkscreen Bottom")
		(1 "F.Mask" user "Board Geometry/Soldermask Top")
		(3 "B.Mask" user "Board Geometry/Soldermask Bottom")
		(17 "Dwgs.User" user "User.Drawings")
		(19 "Cmts.User" user "User.Comments")
		(21 "Eco1.User" user "User.Eco1")
		(23 "Eco2.User" user "User.Eco2")
		(25 "Edge.Cuts" user "Board Geometry/Outline")
		(27 "Margin" user)
		(31 "F.CrtYd" user "Package Geometry/Place Bound Top")
		(29 "B.CrtYd" user "Package Geometry/Place Bound Bottom")
		(35 "F.Fab" user "Ref Des/Assembly Top")
		(33 "B.Fab" user "Ref Des/Assembly Bottom")
	)
	(footprint ""
		(layer "B.Cu")
		(at 138.049 -105.283 -90)
		(property "Reference" "R138"
			(at 2.45237 0.254 0)
			(unlocked yes)
			(layer "B.SilkS")
			(effects
				(font
					(size 0.7874 0.5842)
					(thickness 0.1524)
				)
				(justify mirror)
			)
		)
		(property "Value" "VAL*"
			(at -0.02032 2.13233 270)
			(unlocked yes)
			(layer "B.Fab")
			(hide yes)
			(effects
				(font
					(size 0.7874 0.5842)
					(thickness 0.1524)
				)
				(justify mirror)
			)
		)
		(property "Tolerance" "TOL*"
			(at -0.044704 3.05435 270)
			(unlocked yes)
			(layer "Cmts.User")
			(hide yes)
			(effects
				(font
					(size 0.7874 0.5842)
					(thickness 0.1524)
				)
				(justify mirror)
			)
		)
		(property "User Part Number" "PARTNUM*"
			(at -0.02032 4.024884 270)
			(unlocked yes)
			(layer "Cmts.User")
			(hide yes)
			(effects
				(font
					(size 0.7874 0.5842)
					(thickness 0.1524)
				)
				(justify mirror)
			)
		)
		(property "Device Type" "RESISTOR-G155-13300-01,330OHM,A"
			(at -0.008382 1.210564 270)
			(unlocked yes)
			(layer "B.Fab")
			(hide yes)
			(effects
				(font
					(size 0.7874 0.5842)
					(thickness 0.1524)
				)
				(justify mirror)
			)
		)
		(duplicate_pad_numbers_are_jumpers no)
		(fp_line
			(start -1.143 0.5588)
			(end -1.143 -0.5588)
			(stroke
				(width 0.1)
				(type default)
			)
			(layer "B.SilkS")
		)
		(fp_line
			(start 1.143 0.5588)
			(end -1.143 0.5588)
			(stroke
				(width 0.1)
				(type default)
			)
			(layer "B.SilkS")
		)
		(fp_line
			(start -1.143 -0.5588)
			(end 1.143 -0.5588)
			(stroke
				(width 0.1)
				(type default)
			)
			(layer "B.SilkS")
		)
		(fp_line
			(start 1.143 -0.5588)
			(end 1.143 0.5588)
			(stroke
				(width 0.1)
				(type default)
			)
			(layer "B.SilkS")
		)
		(fp_rect
			(start -1.143 -0.5588)
			(end 1.143 0.5588)
			(stroke
				(width 0)
				(type default)
			)
			(fill no)
			(layer "B.CrtYd")
		)
		(fp_line
			(start -0.508 0.3048)
			(end -0.508 -0.3048)
			(stroke
				(width 0.1)
				(type default)
			)
			(layer "B.Fab")
		)
		(fp_line
			(start 0.508 0.3048)
			(end -0.508 0.3048)
			(stroke
				(width 0.1)
				(type default)
			)
			(layer "B.Fab")
		)
		(fp_line
			(start -0.508 -0.3048)
			(end 0.508 -0.3048)
			(stroke
				(width 0.1)
				(type default)
			)
			(layer "B.Fab")
		)
		(fp_line
			(start 0.508 -0.3048)
			(end 0.508 0.3048)
			(stroke
				(width 0.1)
				(type default)
			)
			(layer "B.Fab")
		)
		(pad "1" smd rect
			(at 0.5334 0 90)
			(size 0.7112 0.6096)
			(layers "B.Cu" "B.Mask" "B.Paste")
			(net "UNNAMED_14_OPTICAL_I140_A")
		)
		(pad "2" smd rect
			(at -0.5334 0 90)
			(size 0.7112 0.6096)
			(layers "B.Cu" "B.Mask" "B.Paste")
			(net "XP3R3V_FPGA")
		)
		(zone
			(layer "B.Cu")
			(hatch none 0.5)
			(connect_pads
				(clearance 0)
			)
			(min_thickness 0.25)
			(keepout
				(tracks allowed)
				(vias not_allowed)
				(pads allowed)
				(copperpour not_allowed)
				(footprints allowed)
			)
			(placement
				(enabled no)
				(sheetname "")
			)
			(fill
				(thermal_gap 0.5)
				(thermal_bridge_width 0.5)
				(island_removal_mode 0)
			)
			(polygon
				(pts
					(xy 138.3538 -105.3592) (xy 137.7442 -105.3592) (xy 137.7442 -105.2068) (xy 138.3538 -105.2068)
				)
			)
		)
	)
	(footprint ""
		(layer "B.Cu")
		(at 140.335 -70.358)
		(property "Reference" "R135"
			(at -4.572 -0.34163 0)
			(unlocked yes)
			(layer "B.SilkS")
			(effects
				(font
					(size 0.7874 0.5842)
					(thickness 0.1524)
				)
				(justify mirror)
			)
		)
		(property "Value" "VAL*"
			(at -0.02032 2.13233 0)
			(unlocked yes)
			(layer "B.Fab")
			(hide yes)
			(effects
				(font
					(size 0.7874 0.5842)
					(thickness 0.1524)
				)
				(justify mirror)
			)
		)
		(property "Device Type" "RESISTOR-G155-100R0-J0,0OHM,-"
			(at -0.008382 1.210564 0)
			(unlocked yes)
			(layer "B.Fab")
			(hide yes)
			(effects
				(font
					(size 0.7874 0.5842)
					(thickness 0.1524)
				)
				(justify mirror)
			)
		)
		(property "User Part Number" "PARTNUM*"
			(at -0.02032 4.024884 0)
			(unlocked yes)
			(layer "Cmts.User")
			(hide yes)
			(effects
				(font
					(size 0.7874 0.5842)
					(thickness 0.1524)
				)
				(justify mirror)
			)
		)
		(property "Tolerance" "TOL*"
			(at -0.044704 3.05435 0)
			(unlocked yes)
			(layer "Cmts.User")
			(hide yes)
			(effects
				(font
					(size 0.7874 0.5842)
					(thickness 0.1524)
				)
				(justify mirror)
			)
		)
		(duplicate_pad_numbers_are_jumpers no)
		(fp_line
			(start -1.143 -0.5588)
			(end 1.143 -0.5588)
			(stroke
				(width 0.1)
				(type default)
			)
			(layer "B.SilkS")
		)
		(fp_line
			(start -1.143 0.5588)
			(end -1.143 -0.5588)
			(stroke
				(width 0.1)
				(type default)
			)
			(layer "B.SilkS")
		)
		(fp_line
			(start 1.143 -0.5588)
			(end 1.143 0.5588)
			(stroke
				(width 0.1)
				(type default)
			)
			(layer "B.SilkS")
		)
		(fp_line
			(start 1.143 0.5588)
			(end -1.143 0.5588)
			(stroke
				(width 0.1)
				(type default)
			)
			(layer "B.SilkS")
		)
		(fp_rect
			(start -1.143 -0.5588)
			(end 1.143 0.5588)
			(stroke
				(width 0)
				(type default)
			)
			(fill no)
			(layer "B.CrtYd")
		)
		(fp_line
			(start -0.508 -0.3048)
			(end 0.508 -0.3048)
			(stroke
				(width 0.1)
				(type default)
			)
			(layer "B.Fab")
		)
		(fp_line
			(start -0.508 0.3048)
			(end -0.508 -0.3048)
			(stroke
				(width 0.1)
				(type default)
			)
			(layer "B.Fab")
		)
		(fp_line
			(start 0.508 -0.3048)
			(end 0.508 0.3048)
			(stroke
				(width 0.1)
				(type default)
			)
			(layer "B.Fab")
		)
		(fp_line
			(start 0.508 0.3048)
			(end -0.508 0.3048)
			(stroke
				(width 0.1)
				(type default)
			)
			(layer "B.Fab")
		)
		(pad "1" smd rect
			(at 0.5334 0 180)
			(size 0.7112 0.6096)
			(layers "B.Cu" "B.Mask" "B.Paste")
			(net "FT4232_FPGA_TDO")
		)
		(pad "2" smd rect
			(at -0.5334 0 180)
			(size 0.7112 0.6096)
			(layers "B.Cu" "B.Mask" "B.Paste")
			(net "FPGA_TDO")
		)
		(zone
			(layer "B.Cu")
			(hatch none 0.5)
			(connect_pads
				(clearance 0)
			)
			(min_thickness 0.25)
			(keepout
				(tracks allowed)
				(vias not_allowed)
				(pads allowed)
				(copperpour not_allowed)
				(footprints allowed)
			)
			(placement
				(enabled no)
				(sheetname "")
			)
			(fill
				(thermal_gap 0.5)
				(thermal_bridge_width 0.5)
				(island_removal_mode 0)
			)
			(polygon
				(pts
					(xy 140.2588 -70.6628) (xy 140.2588 -70.0532) (xy 140.4112 -70.0532) (xy 140.4112 -70.6628)
				)
			)
		)
	)
	(footprint ""
		(layer "B.Cu")
		(at 90.2716 -49.059846 180)
		(property "Reference" "R105"
			(at -0.762 2.500884 0)
			(unlocked yes)
			(layer "B.SilkS")
			(effects
				(font
					(size 0.7874 0.5842)
					(thickness 0.1524)
				)
				(justify mirror)
			)
		)
		(property "Value" "VAL*"
			(at -0.02032 2.13233 180)
			(unlocked yes)
			(layer "B.Fab")
			(hide yes)
			(effects
				(font
					(size 0.7874 0.5842)
					(thickness 0.1524)
				)
				(justify mirror)
			)
		)
		(property "Device Type" "RESISTOR-G155-100R0-J0,0OHM,-"
			(at -0.008382 1.210564 180)
			(unlocked yes)
			(layer "B.Fab")
			(hide yes)
			(effects
				(font
					(size 0.7874 0.5842)
					(thickness 0.1524)
				)
				(justify mirror)
			)
		)
		(property "User Part Number" "PARTNUM*"
			(at -0.02032 4.024884 180)
			(unlocked yes)
			(layer "Cmts.User")
			(hide yes)
			(effects
				(font
					(size 0.7874 0.5842)
					(thickness 0.1524)
				)
				(justify mirror)
			)
		)
		(property "Tolerance" "TOL*"
			(at -0.044704 3.05435 180)
			(unlocked yes)
			(layer "Cmts.User")
			(hide yes)
			(effects
				(font
					(size 0.7874 0.5842)
					(thickness 0.1524)
				)
				(justify mirror)
			)
		)
		(duplicate_pad_numbers_are_jumpers no)
		(fp_line
			(start 1.143 0.5588)
			(end -1.143 0.5588)
			(stroke
				(width 0.1)
				(type default)
			)
			(layer "B.SilkS")
		)
		(fp_line
			(start 1.143 -0.5588)
			(end 1.143 0.5588)
			(stroke
				(width 0.1)
				(type default)
			)
			(layer "B.SilkS")
		)
		(fp_line
			(start -1.143 0.5588)
			(end -1.143 -0.5588)
			(stroke
				(width 0.1)
				(type default)
			)
			(layer "B.SilkS")
		)
		(fp_line
			(start -1.143 -0.5588)
			(end 1.143 -0.5588)
			(stroke
				(width 0.1)
				(type default)
			)
			(layer "B.SilkS")
		)
		(fp_rect
			(start 1.143 -0.5588)
			(end -1.143 0.5588)
			(stroke
				(width 0)
				(type default)
			)
			(fill no)
			(layer "B.CrtYd")
		)
		(fp_line
			(start 0.508 0.3048)
			(end -0.508 0.3048)
			(stroke
				(width 0.1)
				(type default)
			)
			(layer "B.Fab")
		)
		(fp_line
			(start 0.508 -0.3048)
			(end 0.508 0.3048)
			(stroke
				(width 0.1)
				(type default)
			)
			(layer "B.Fab")
		)
		(fp_line
			(start -0.508 0.3048)
			(end -0.508 -0.3048)
			(stroke
				(width 0.1)
				(type default)
			)
			(layer "B.Fab")
		)
		(fp_line
			(start -0.508 -0.3048)
			(end 0.508 -0.3048)
			(stroke
				(width 0.1)
				(type default)
			)
			(layer "B.Fab")
		)
		(pad "1" smd rect
			(at 0.5334 0)
			(size 0.7112 0.6096)
			(layers "B.Cu" "B.Mask" "B.Paste")
			(net "MUX_USB_DM")
		)
		(pad "2" smd rect
			(at -0.5334 0)
			(size 0.7112 0.6096)
			(layers "B.Cu" "B.Mask" "B.Paste")
			(net "MAC_USB_DM")
		)
		(zone
			(layer "B.Cu")
			(hatch none 0.5)
			(connect_pads
				(clearance 0)
			)
			(min_thickness 0.25)
			(keepout
				(tracks allowed)
				(vias not_allowed)
				(pads allowed)
				(copperpour not_allowed)
				(footprints allowed)
			)
			(placement
				(enabled no)
				(sheetname "")
			)
			(fill
				(thermal_gap 0.5)
				(thermal_bridge_width 0.5)
				(island_removal_mode 0)
			)
			(polygon
				(pts
					(xy 90.1954 -48.755046) (xy 90.3478 -48.755046) (xy 90.3478 -49.364646) (xy 90.1954 -49.364646)
				)
			)
		)
	)
	(footprint ""
		(layer "B.Cu")
		(at 41.4274 -102.3874)
		(property "Reference" "SP1"
			(at 0.0762 1.18237 0)
			(unlocked yes)
			(layer "B.SilkS")
			(effects
				(font
					(size 0.7874 0.5842)
					(thickness 0.1524)
				)
				(justify mirror)
			)
		)
		(property "Value" ""
			(at 0 0 0)
			(layer "B.Fab")
			(effects
				(font
					(size 1.27 1.27)
				)
				(justify mirror)
			)
		)
		(duplicate_pad_numbers_are_jumpers no)
		(fp_rect
			(start 0.1778 -0.3048)
			(end -0.1778 0.3048)
			(stroke
				(width 0)
				(type default)
			)
			(fill yes)
			(layer "B.Paste")
		)
		(fp_rect
			(start 0.2286 -0.3556)
			(end -0.2286 0.3556)
			(stroke
				(width 0)
				(type default)
			)
			(fill no)
			(layer "B.CrtYd")
		)
		(fp_line
			(start -0.1397 -0.2413)
			(end -0.1397 0.2413)
			(stroke
				(width 0.1)
				(type default)
			)
			(layer "B.Fab")
		)
		(fp_line
			(start -0.1397 0.2413)
			(end 0.1397 0.2413)
			(stroke
				(width 0.1)
				(type default)
			)
			(layer "B.Fab")
		)
		(fp_line
			(start 0.1397 -0.2413)
			(end -0.1397 -0.2413)
			(stroke
				(width 0.1)
				(type default)
			)
			(layer "B.Fab")
		)
		(fp_line
			(start 0.1397 0.2413)
			(end 0.1397 -0.2413)
			(stroke
				(width 0.1)
				(type default)
			)
			(layer "B.Fab")
		)
		(pad "1" smd rect
			(at 0.1143 0 180)
			(size 0.127 0.6096)
			(layers "B.Cu" "B.Mask" "B.Paste")
			(net "SG")
		)
		(pad "2" smd rect
			(at -0.1143 0 180)
			(size 0.127 0.6096)
			(layers "B.Cu" "B.Mask" "B.Paste")
			(net "XP5R0V_AGND")
		)
	)
	(footprint ""
		(layer "B.Cu")
		(at 113.68659 -56.388)
		(property "Reference" "C163"
			(at 1.59766 -0.635 270)
			(unlocked yes)
			(layer "B.SilkS")
			(effects
				(font
					(size 0.635 0.4064)
					(thickness 0.1524)
				)
				(justify mirror)
			)
		)
		(property "Value" "VAL*"
			(at -0.02032 2.13233 0)
			(unlocked yes)
			(layer "B.Fab")
			(hide yes)
			(effects
				(font
					(size 0.7874 0.5842)
					(thickness 0.1524)
				)
				(justify mirror)
			)
		)
		(property "Device Type" "CAPACITOR-G105-0F475-BM,4.7UF,A"
			(at -0.008382 1.210564 0)
			(unlocked yes)
			(layer "B.Fab")
			(hide yes)
			(effects
				(font
					(size 0.7874 0.5842)
					(thickness 0.1524)
				)
				(justify mirror)
			)
		)
		(property "User Part Number" "PARTNUM*"
			(at -0.02032 4.024884 0)
			(unlocked yes)
			(layer "Cmts.User")
			(hide yes)
			(effects
				(font
					(size 0.7874 0.5842)
					(thickness 0.1524)
				)
				(justify mirror)
			)
		)
		(property "Tolerance" "TOL*"
			(at -0.044704 3.05435 0)
			(unlocked yes)
			(layer "Cmts.User")
			(hide yes)
			(effects
				(font
					(size 0.7874 0.5842)
					(thickness 0.1524)
				)
				(justify mirror)
			)
		)
		(duplicate_pad_numbers_are_jumpers no)
		(fp_line
			(start -1.143 -0.5588)
			(end 1.143 -0.5588)
			(stroke
				(width 0.1)
				(type default)
			)
			(layer "B.SilkS")
		)
		(fp_line
			(start -1.143 0.5588)
			(end -1.143 -0.5588)
			(stroke
				(width 0.1)
				(type default)
			)
			(layer "B.SilkS")
		)
		(fp_line
			(start 1.143 -0.5588)
			(end 1.143 0.5588)
			(stroke
				(width 0.1)
				(type default)
			)
			(layer "B.SilkS")
		)
		(fp_line
			(start 1.143 0.5588)
			(end -1.143 0.5588)
			(stroke
				(width 0.1)
				(type default)
			)
			(layer "B.SilkS")
		)
		(fp_rect
			(start -1.143 0.5588)
			(end 1.143 -0.5588)
			(stroke
				(width 0)
				(type default)
			)
			(fill no)
			(layer "B.CrtYd")
		)
		(fp_line
			(start -0.508 -0.3048)
			(end 0.508 -0.3048)
			(stroke
				(width 0.1)
				(type default)
			)
			(layer "B.Fab")
		)
		(fp_line
			(start -0.508 0.3048)
			(end -0.508 -0.3048)
			(stroke
				(width 0.1)
				(type default)
			)
			(layer "B.Fab")
		)
		(fp_line
			(start 0.508 -0.3048)
			(end 0.508 0.3048)
			(stroke
				(width 0.1)
				(type default)
			)
			(layer "B.Fab")
		)
		(fp_line
			(start 0.508 0.3048)
			(end -0.508 0.3048)
			(stroke
				(width 0.1)
				(type default)
			)
			(layer "B.Fab")
		)
		(pad "1" smd rect
			(at 0.5334 0 180)
			(size 0.7112 0.6096)
			(layers "B.Cu" "B.Mask" "B.Paste")
			(net "XP3R3V_FPGA")
		)
		(pad "2" smd rect
			(at -0.5334 0 180)
			(size 0.7112 0.6096)
			(layers "B.Cu" "B.Mask" "B.Paste")
			(net "SG")
		)
		(zone
			(layer "B.Cu")
			(hatch none 0.5)
			(connect_pads
				(clearance 0)
			)
			(min_thickness 0.25)
			(keepout
				(tracks allowed)
				(vias not_allowed)
				(pads allowed)
				(copperpour not_allowed)
				(footprints allowed)
			)
			(placement
				(enabled no)
				(sheetname "")
			)
			(fill
				(thermal_gap 0.5)
				(thermal_bridge_width 0.5)
				(island_removal_mode 0)
			)
			(polygon
				(pts
					(xy 113.61039 -56.0832) (xy 113.76279 -56.0832) (xy 113.76279 -56.6928) (xy 113.61039 -56.6928)
				)
			)
		)
	)
	(footprint ""
		(layer "B.Cu")
		(at 54.0512 -74.9808 90)
		(property "Reference" "R413"
			(at 4.064 0.08763 270)
			(unlocked yes)
			(layer "B.SilkS")
			(effects
				(font
					(size 0.7874 0.5842)
					(thickness 0.1524)
				)
				(justify mirror)
			)
		)
		(property "Value" "VAL*"
			(at -0.02032 2.13233 90)
			(unlocked yes)
			(layer "B.Fab")
			(hide yes)
			(effects
				(font
					(size 0.7874 0.5842)
					(thickness 0.1524)
				)
				(justify mirror)
			)
		)
		(property "Device Type" "RESISTOR-G155-11001-01,1KOHM,1%"
			(at -0.008382 1.210564 90)
			(unlocked yes)
			(layer "B.Fab")
			(hide yes)
			(effects
				(font
					(size 0.7874 0.5842)
					(thickness 0.1524)
				)
				(justify mirror)
			)
		)
		(property "User Part Number" "PARTNUM*"
			(at -0.02032 4.024884 90)
			(unlocked yes)
			(layer "Cmts.User")
			(hide yes)
			(effects
				(font
					(size 0.7874 0.5842)
					(thickness 0.1524)
				)
				(justify mirror)
			)
		)
		(property "Tolerance" "TOL*"
			(at -0.044704 3.05435 90)
			(unlocked yes)
			(layer "Cmts.User")
			(hide yes)
			(effects
				(font
					(size 0.7874 0.5842)
					(thickness 0.1524)
				)
				(justify mirror)
			)
		)
		(duplicate_pad_numbers_are_jumpers no)
		(fp_line
			(start 1.143 -0.5588)
			(end 1.143 0.5588)
			(stroke
				(width 0.1)
				(type default)
			)
			(layer "B.SilkS")
		)
		(fp_line
			(start -1.143 -0.5588)
			(end 1.143 -0.5588)
			(stroke
				(width 0.1)
				(type default)
			)
			(layer "B.SilkS")
		)
		(fp_line
			(start 1.143 0.5588)
			(end -1.143 0.5588)
			(stroke
				(width 0.1)
				(type default)
			)
			(layer "B.SilkS")
		)
		(fp_line
			(start -1.143 0.5588)
			(end -1.143 -0.5588)
			(stroke
				(width 0.1)
				(type default)
			)
			(layer "B.SilkS")
		)
		(fp_rect
			(start 1.143 0.5588)
			(end -1.143 -0.5588)
			(stroke
				(width 0)
				(type default)
			)
			(fill no)
			(layer "B.CrtYd")
		)
		(fp_line
			(start 0.508 -0.3048)
			(end 0.508 0.3048)
			(stroke
				(width 0.1)
				(type default)
			)
			(layer "B.Fab")
		)
		(fp_line
			(start -0.508 -0.3048)
			(end 0.508 -0.3048)
			(stroke
				(width 0.1)
				(type default)
			)
			(layer "B.Fab")
		)
		(fp_line
			(start 0.508 0.3048)
			(end -0.508 0.3048)
			(stroke
				(width 0.1)
				(type default)
			)
			(layer "B.Fab")
		)
		(fp_line
			(start -0.508 0.3048)
			(end -0.508 -0.3048)
			(stroke
				(width 0.1)
				(type default)
			)
			(layer "B.Fab")
		)
		(pad "1" smd rect
			(at 0.5334 0 270)
			(size 0.7112 0.6096)
			(layers "B.Cu" "B.Mask" "B.Paste")
			(net "UNNAMED_6_LM75BDPTSSOP8_I59_A1")
		)
		(pad "2" smd rect
			(at -0.5334 0 270)
			(size 0.7112 0.6096)
			(layers "B.Cu" "B.Mask" "B.Paste")
			(net "SG")
		)
		(zone
			(layer "B.Cu")
			(hatch none 0.5)
			(connect_pads
				(clearance 0)
			)
			(min_thickness 0.25)
			(keepout
				(tracks not_allowed)
				(vias allowed)
				(pads allowed)
				(copperpour not_allowed)
				(footprints allowed)
			)
			(placement
				(enabled no)
				(sheetname "")
			)
			(fill
				(thermal_gap 0.5)
				(thermal_bridge_width 0.5)
				(island_removal_mode 0)
			)
			(polygon
				(pts
					(xy 54.356 -75.057) (xy 53.7464 -75.057) (xy 53.7464 -74.9046) (xy 54.356 -74.9046)
				)
			)
		)
		(zone
			(layer "B.Cu")
			(hatch none 0.5)
			(connect_pads
				(clearance 0)
			)
			(min_thickness 0.25)
			(keepout
				(tracks allowed)
				(vias not_allowed)
				(pads allowed)
				(copperpour not_allowed)
				(footprints allowed)
			)
			(placement
				(enabled no)
				(sheetname "")
			)
			(fill
				(thermal_gap 0.5)
				(thermal_bridge_width 0.5)
				(island_removal_mode 0)
			)
			(polygon
				(pts
					(xy 54.356 -75.057) (xy 53.7464 -75.057) (xy 53.7464 -74.9046) (xy 54.356 -74.9046)
				)
			)
		)
	)
)
